(kicad_pcb
	(version 20260206)
	(generator "pcbnew")
	(generator_version "10.0")
	(general
		(thickness 1.6)
		(legacy_teardrops no)
	)
	(paper "A4")
	(title_block
		(title "03242023_DA0F0TMBIJ0_F0T_Motherboard_J_brd_V01_OCP.brd")
		(comment 1 "Grand Teton / footprints 1522-1528 of 6105")
	)
	(layers
		(0 "F.Cu" signal "TOP")
		(4 "In1.Cu" signal "GND")
		(6 "In2.Cu" signal "IN1")
		(8 "In3.Cu" signal "GND1")
		(10 "In4.Cu" signal "IN2")
		(12 "In5.Cu" signal "GND2")
		(14 "In6.Cu" signal "IN3")
		(16 "In7.Cu" signal "GND3")
		(18 "In8.Cu" signal "VCC")
		(20 "In9.Cu" signal "VCC1")
		(22 "In10.Cu" signal "GND4")
		(24 "In11.Cu" signal "IN4")
		(26 "In12.Cu" signal "GND5")
		(28 "In13.Cu" signal "IN5")
		(30 "In14.Cu" signal "GND6")
		(32 "In15.Cu" signal "IN6")
		(34 "In16.Cu" signal "GND7")
		(2 "B.Cu" signal "BOTTOM")
		(9 "F.Adhes" user "F.Adhesive")
		(11 "B.Adhes" user "B.Adhesive")
		(13 "F.Paste" user "Package Geometry/Pastemask Top")
		(15 "B.Paste" user "Package Geometry/Pastemask Bottom")
		(5 "F.SilkS" user "Ref Des/Silkscreen Top")
		(7 "B.SilkS" user "Ref Des/Silkscreen Bottom")
		(1 "F.Mask" user "Board Geometry/Soldermask Top")
		(3 "B.Mask" user "Board Geometry/Soldermask Bottom")
		(17 "Dwgs.User" user "User.Drawings")
		(19 "Cmts.User" user "User.Comments")
		(21 "Eco1.User" user "User.Eco1")
		(23 "Eco2.User" user "User.Eco2")
		(25 "Edge.Cuts" user "Board Geometry/Outline")
		(27 "Margin" user)
		(31 "F.CrtYd" user "Package Geometry/Place Bound Top")
		(29 "B.CrtYd" user "Package Geometry/Place Bound Bottom")
		(35 "F.Fab" user "Ref Des/Assembly Top")
		(33 "B.Fab" user "Ref Des/Assembly Bottom")
	)
	(footprint ""
		(layer "F.Cu")
		(at 69.923406 -160.499806)
		(property "Reference" "PC1595"
			(at 0 0 0)
			(layer "F.SilkS")
			(hide yes)
			(effects
				(font
					(size 1.27 1.27)
				)
			)
		)
		(property "Value" ""
			(at 0 0 0)
			(layer "F.Fab")
			(effects
				(font
					(size 1.27 1.27)
				)
			)
		)
		(duplicate_pad_numbers_are_jumpers no)
		(fp_line
			(start 2.750058 0.999998)
			(end -2.750058 0.999998)
			(stroke
				(width 0.1524)
				(type default)
			)
			(layer "F.SilkS")
		)
		(fp_circle
			(center 0 0.999998)
			(end 2.750058 0.999998)
			(stroke
				(width 0.1524)
				(type default)
			)
			(fill no)
			(layer "F.SilkS")
		)
		(fp_poly
			(pts
				(arc
					(start 2.750058 0.999998)
					(mid 0 3.750056)
					(end -2.750058 0.999998)
				)
			)
			(stroke
				(width 0)
				(type default)
			)
			(fill yes)
			(layer "F.SilkS")
		)
		(fp_circle
			(center 0 0.999998)
			(end 2.750058 0.999998)
			(stroke
				(width 0.1)
				(type default)
			)
			(fill no)
			(layer "F.Fab")
		)
		(pad "1" thru_hole rect
			(at 0 0)
			(size 1.5748 1.5748)
			(drill 1.0668)
			(layers "*.Cu" "*.Mask")
			(remove_unused_layers no)
			(net "PVCCINFAON_CPU1")
			(clearance 0)
			(padstack
				(mode front_inner_back)
				(layer "Inner"
					(shape circle)
					(size 1.5748 1.5748)
					(clearance 0)
				)
				(layer "B.Cu"
					(shape rect)
					(size 1.5748 1.5748)
					(clearance 0)
				)
			)
		)
		(pad "2" thru_hole circle
			(at 0 1.999996)
			(size 1.5748 1.5748)
			(drill 1.0668)
			(layers "*.Cu" "*.Mask")
			(remove_unused_layers no)
			(net "GND")
			(clearance 0)
		)
	)
	(footprint ""
		(layer "F.Cu")
		(at 108.016802 -96.317054)
		(property "Reference" "Q76"
			(at 2.043938 -1.909064 0)
			(unlocked yes)
			(layer "F.SilkS")
			(effects
				(font
					(size 0.7874 0.5842)
					(thickness 0.1524)
				)
				(justify left)
			)
		)
		(property "Value" ""
			(at 0 0 0)
			(layer "F.Fab")
			(effects
				(font
					(size 1.27 1.27)
				)
			)
		)
		(duplicate_pad_numbers_are_jumpers no)
		(fp_line
			(start -1.332738 -1.100074)
			(end -0.4826 -1.100074)
			(stroke
				(width 0.1524)
				(type default)
			)
			(layer "F.SilkS")
		)
		(fp_line
			(start -1.332738 1.100074)
			(end -1.332738 -1.100074)
			(stroke
				(width 0.1524)
				(type default)
			)
			(layer "F.SilkS")
		)
		(fp_line
			(start -0.4826 -1.100074)
			(end 0 -0.541274)
			(stroke
				(width 0.1524)
				(type default)
			)
			(layer "F.SilkS")
		)
		(fp_line
			(start 0 -0.541274)
			(end 0.4826 -1.100074)
			(stroke
				(width 0.1524)
				(type default)
			)
			(layer "F.SilkS")
		)
		(fp_line
			(start 0.4826 -1.100074)
			(end 1.332738 -1.100074)
			(stroke
				(width 0.1524)
				(type default)
			)
			(layer "F.SilkS")
		)
		(fp_line
			(start 1.332738 -1.100074)
			(end 1.332738 1.100074)
			(stroke
				(width 0.1524)
				(type default)
			)
			(layer "F.SilkS")
		)
		(fp_line
			(start 1.332738 1.100074)
			(end -1.332738 1.100074)
			(stroke
				(width 0.1524)
				(type default)
			)
			(layer "F.SilkS")
		)
		(fp_poly
			(pts
				(xy -0.673862 -2.001012) (xy -1.02489 -1.298956) (xy -1.375918 -2.001012)
			)
			(stroke
				(width 0)
				(type default)
			)
			(fill yes)
			(layer "F.SilkS")
		)
		(fp_line
			(start -0.674878 -1.100074)
			(end 0.674878 -1.100074)
			(stroke
				(width 0.1)
				(type default)
			)
			(layer "F.Fab")
		)
		(fp_line
			(start -0.674878 1.100074)
			(end -0.674878 -1.100074)
			(stroke
				(width 0.1)
				(type default)
			)
			(layer "F.Fab")
		)
		(fp_line
			(start 0.674878 -1.100074)
			(end 0.674878 1.100074)
			(stroke
				(width 0.1)
				(type default)
			)
			(layer "F.Fab")
		)
		(fp_line
			(start 0.674878 1.100074)
			(end -0.674878 1.100074)
			(stroke
				(width 0.1)
				(type default)
			)
			(layer "F.Fab")
		)
		(fp_poly
			(pts
				(xy -2.2352 -0.298958) (xy -2.2352 -1.001014) (xy -1.533144 -0.649986)
			)
			(stroke
				(width 0)
				(type default)
			)
			(fill yes)
			(layer "F.Fab")
		)
		(pad "1" smd rect
			(at -0.94996 -0.649986 90)
			(size 0.4318 0.508)
			(layers "F.Cu" "F.Mask" "F.Paste")
			(net "GND")
		)
		(pad "2" smd rect
			(at -0.94996 0 90)
			(size 0.4318 0.508)
			(layers "F.Cu" "F.Mask" "F.Paste")
			(net "PWRGD_P1V8_PCH_AUX")
		)
		(pad "3" smd rect
			(at -0.94996 0.649986 90)
			(size 0.4318 0.508)
			(layers "F.Cu" "F.Mask" "F.Paste")
			(net "LED_PWRGD_P1V05_PCH_AUX_D")
		)
		(pad "4" smd rect
			(at 0.94996 0.649986 90)
			(size 0.4318 0.508)
			(layers "F.Cu" "F.Mask" "F.Paste")
			(net "GND")
		)
		(pad "5" smd rect
			(at 0.94996 0 90)
			(size 0.4318 0.508)
			(layers "F.Cu" "F.Mask" "F.Paste")
			(net "PWRGD_P1V05_PCH_AUX")
		)
		(pad "6" smd rect
			(at 0.94996 -0.649986 90)
			(size 0.4318 0.508)
			(layers "F.Cu" "F.Mask" "F.Paste")
			(net "LED_PWRGD_P1V8_PCH_AUX_D")
		)
	)
	(footprint ""
		(layer "F.Cu")
		(at 128.016 -61.432948 180)
		(property "Reference" "R4634"
			(at 0 0 180)
			(layer "F.SilkS")
			(hide yes)
			(effects
				(font
					(size 1.27 1.27)
				)
			)
		)
		(property "Value" ""
			(at 0 0 180)
			(layer "F.Fab")
			(effects
				(font
					(size 1.27 1.27)
				)
			)
		)
		(duplicate_pad_numbers_are_jumpers no)
		(fp_line
			(start 0.7874 0.4064)
			(end -0.7874 0.4064)
			(stroke
				(width 0.1524)
				(type default)
			)
			(layer "F.SilkS")
		)
		(fp_line
			(start 0.7874 -0.4064)
			(end 0.7874 0.4064)
			(stroke
				(width 0.1524)
				(type default)
			)
			(layer "F.SilkS")
		)
		(fp_line
			(start -0.7874 0.4064)
			(end -0.7874 -0.4064)
			(stroke
				(width 0.1524)
				(type default)
			)
			(layer "F.SilkS")
		)
		(fp_line
			(start -0.7874 -0.4064)
			(end 0.7874 -0.4064)
			(stroke
				(width 0.1524)
				(type default)
			)
			(layer "F.SilkS")
		)
		(fp_line
			(start 0.67945 0.3048)
			(end 0.120396 0.3048)
			(stroke
				(width 0.1)
				(type default)
			)
			(layer "F.Fab")
		)
		(fp_line
			(start 0.67945 -0.3048)
			(end 0.67945 0.3048)
			(stroke
				(width 0.1)
				(type default)
			)
			(layer "F.Fab")
		)
		(fp_line
			(start 0.12065 -0.2794)
			(end 0.12065 -0.3048)
			(stroke
				(width 0.1)
				(type default)
			)
			(layer "F.Fab")
		)
		(fp_line
			(start 0.12065 -0.3048)
			(end 0.67945 -0.3048)
			(stroke
				(width 0.1)
				(type default)
			)
			(layer "F.Fab")
		)
		(fp_line
			(start 0.120396 0.3048)
			(end 0.120396 0.2794)
			(stroke
				(width 0.1)
				(type default)
			)
			(layer "F.Fab")
		)
		(fp_line
			(start 0.120396 0.2794)
			(end -0.12065 0.2794)
			(stroke
				(width 0.1)
				(type default)
			)
			(layer "F.Fab")
		)
		(fp_line
			(start -0.12065 0.3048)
			(end -0.67945 0.3048)
			(stroke
				(width 0.1)
				(type default)
			)
			(layer "F.Fab")
		)
		(fp_line
			(start -0.12065 0.2794)
			(end -0.12065 0.3048)
			(stroke
				(width 0.1)
				(type default)
			)
			(layer "F.Fab")
		)
		(fp_line
			(start -0.12065 -0.2794)
			(end 0.12065 -0.2794)
			(stroke
				(width 0.1)
				(type default)
			)
			(layer "F.Fab")
		)
		(fp_line
			(start -0.12065 -0.305054)
			(end -0.12065 -0.2794)
			(stroke
				(width 0.1)
				(type default)
			)
			(layer "F.Fab")
		)
		(fp_line
			(start -0.67945 0.3048)
			(end -0.67945 -0.305054)
			(stroke
				(width 0.1)
				(type default)
			)
			(layer "F.Fab")
		)
		(fp_line
			(start -0.67945 -0.305054)
			(end -0.12065 -0.305054)
			(stroke
				(width 0.1)
				(type default)
			)
			(layer "F.Fab")
		)
		(pad "1" smd circle
			(at -0.40005 0 180)
			(size 0 0)
			(layers "F.Cu" "F.Mask" "F.Paste")
			(net "P3V3_AUX")
		)
		(pad "2" smd circle
			(at 0.40005 0 180)
			(size 0 0)
			(layers "F.Cu" "F.Mask" "F.Paste")
			(net "JTAG_BMC_SW_OE")
		)
	)
	(footprint ""
		(layer "F.Cu")
		(at 27.03068 -125.368812 180)
		(property "Reference" "PC2367"
			(at 0 0 180)
			(layer "F.SilkS")
			(hide yes)
			(effects
				(font
					(size 1.27 1.27)
				)
			)
		)
		(property "Value" ""
			(at 0 0 180)
			(layer "F.Fab")
			(effects
				(font
					(size 1.27 1.27)
				)
			)
		)
		(duplicate_pad_numbers_are_jumpers no)
		(fp_line
			(start 0.7874 0.4064)
			(end -0.7874 0.4064)
			(stroke
				(width 0.1524)
				(type default)
			)
			(layer "F.SilkS")
		)
		(fp_line
			(start 0.7874 -0.4064)
			(end 0.7874 0.4064)
			(stroke
				(width 0.1524)
				(type default)
			)
			(layer "F.SilkS")
		)
		(fp_line
			(start -0.7874 0.4064)
			(end -0.7874 -0.4064)
			(stroke
				(width 0.1524)
				(type default)
			)
			(layer "F.SilkS")
		)
		(fp_line
			(start -0.7874 -0.4064)
			(end 0.7874 -0.4064)
			(stroke
				(width 0.1524)
				(type default)
			)
			(layer "F.SilkS")
		)
		(fp_line
			(start 0.67945 0.3048)
			(end 0.120396 0.3048)
			(stroke
				(width 0.1)
				(type default)
			)
			(layer "F.Fab")
		)
		(fp_line
			(start 0.67945 -0.3048)
			(end 0.67945 0.3048)
			(stroke
				(width 0.1)
				(type default)
			)
			(layer "F.Fab")
		)
		(fp_line
			(start 0.12065 -0.2794)
			(end 0.12065 -0.3048)
			(stroke
				(width 0.1)
				(type default)
			)
			(layer "F.Fab")
		)
		(fp_line
			(start 0.12065 -0.3048)
			(end 0.67945 -0.3048)
			(stroke
				(width 0.1)
				(type default)
			)
			(layer "F.Fab")
		)
		(fp_line
			(start 0.120396 0.3048)
			(end 0.120396 0.2794)
			(stroke
				(width 0.1)
				(type default)
			)
			(layer "F.Fab")
		)
		(fp_line
			(start 0.120396 0.2794)
			(end -0.12065 0.2794)
			(stroke
				(width 0.1)
				(type default)
			)
			(layer "F.Fab")
		)
		(fp_line
			(start -0.12065 0.3048)
			(end -0.67945 0.3048)
			(stroke
				(width 0.1)
				(type default)
			)
			(layer "F.Fab")
		)
		(fp_line
			(start -0.12065 0.2794)
			(end -0.12065 0.3048)
			(stroke
				(width 0.1)
				(type default)
			)
			(layer "F.Fab")
		)
		(fp_line
			(start -0.12065 -0.2794)
			(end 0.12065 -0.2794)
			(stroke
				(width 0.1)
				(type default)
			)
			(layer "F.Fab")
		)
		(fp_line
			(start -0.12065 -0.305054)
			(end -0.12065 -0.2794)
			(stroke
				(width 0.1)
				(type default)
			)
			(layer "F.Fab")
		)
		(fp_line
			(start -0.67945 0.3048)
			(end -0.67945 -0.305054)
			(stroke
				(width 0.1)
				(type default)
			)
			(layer "F.Fab")
		)
		(fp_line
			(start -0.67945 -0.305054)
			(end -0.12065 -0.305054)
			(stroke
				(width 0.1)
				(type default)
			)
			(layer "F.Fab")
		)
		(pad "1" smd circle
			(at -0.40005 0 180)
			(size 0 0)
			(layers "F.Cu" "F.Mask" "F.Paste")
			(net "PVCCINFAON_CPU1_VCC")
		)
		(pad "2" smd circle
			(at 0.40005 0 180)
			(size 0 0)
			(layers "F.Cu" "F.Mask" "F.Paste")
			(net "GND")
		)
	)
	(footprint ""
		(layer "F.Cu")
		(at 136.3853 -115.38458 180)
		(property "Reference" "R4757"
			(at 0 0 180)
			(layer "F.SilkS")
			(hide yes)
			(effects
				(font
					(size 1.27 1.27)
				)
			)
		)
		(property "Value" ""
			(at 0 0 180)
			(layer "F.Fab")
			(effects
				(font
					(size 1.27 1.27)
				)
			)
		)
		(duplicate_pad_numbers_are_jumpers no)
		(fp_line
			(start 0.7874 0.4064)
			(end -0.7874 0.4064)
			(stroke
				(width 0.1524)
				(type default)
			)
			(layer "F.SilkS")
		)
		(fp_line
			(start 0.7874 -0.4064)
			(end 0.7874 0.4064)
			(stroke
				(width 0.1524)
				(type default)
			)
			(layer "F.SilkS")
		)
		(fp_line
			(start -0.7874 0.4064)
			(end -0.7874 -0.4064)
			(stroke
				(width 0.1524)
				(type default)
			)
			(layer "F.SilkS")
		)
		(fp_line
			(start -0.7874 -0.4064)
			(end 0.7874 -0.4064)
			(stroke
				(width 0.1524)
				(type default)
			)
			(layer "F.SilkS")
		)
		(fp_line
			(start 0.67945 0.3048)
			(end 0.120396 0.3048)
			(stroke
				(width 0.1)
				(type default)
			)
			(layer "F.Fab")
		)
		(fp_line
			(start 0.67945 -0.3048)
			(end 0.67945 0.3048)
			(stroke
				(width 0.1)
				(type default)
			)
			(layer "F.Fab")
		)
		(fp_line
			(start 0.12065 -0.2794)
			(end 0.12065 -0.3048)
			(stroke
				(width 0.1)
				(type default)
			)
			(layer "F.Fab")
		)
		(fp_line
			(start 0.12065 -0.3048)
			(end 0.67945 -0.3048)
			(stroke
				(width 0.1)
				(type default)
			)
			(layer "F.Fab")
		)
		(fp_line
			(start 0.120396 0.3048)
			(end 0.120396 0.2794)
			(stroke
				(width 0.1)
				(type default)
			)
			(layer "F.Fab")
		)
		(fp_line
			(start 0.120396 0.2794)
			(end -0.12065 0.2794)
			(stroke
				(width 0.1)
				(type default)
			)
			(layer "F.Fab")
		)
		(fp_line
			(start -0.12065 0.3048)
			(end -0.67945 0.3048)
			(stroke
				(width 0.1)
				(type default)
			)
			(layer "F.Fab")
		)
		(fp_line
			(start -0.12065 0.2794)
			(end -0.12065 0.3048)
			(stroke
				(width 0.1)
				(type default)
			)
			(layer "F.Fab")
		)
		(fp_line
			(start -0.12065 -0.2794)
			(end 0.12065 -0.2794)
			(stroke
				(width 0.1)
				(type default)
			)
			(layer "F.Fab")
		)
		(fp_line
			(start -0.12065 -0.305054)
			(end -0.12065 -0.2794)
			(stroke
				(width 0.1)
				(type default)
			)
			(layer "F.Fab")
		)
		(fp_line
			(start -0.67945 0.3048)
			(end -0.67945 -0.305054)
			(stroke
				(width 0.1)
				(type default)
			)
			(layer "F.Fab")
		)
		(fp_line
			(start -0.67945 -0.305054)
			(end -0.12065 -0.305054)
			(stroke
				(width 0.1)
				(type default)
			)
			(layer "F.Fab")
		)
		(pad "1" smd circle
			(at -0.40005 0 180)
			(size 0 0)
			(layers "F.Cu" "F.Mask" "F.Paste")
			(net "HP_LVC3_OCP_V3_2_PWRGD_R2")
		)
		(pad "2" smd circle
			(at 0.40005 0 180)
			(size 0 0)
			(layers "F.Cu" "F.Mask" "F.Paste")
			(net "OCP_V3_2_AUX_PWR_EN_R2")
		)
	)
	(footprint ""
		(layer "F.Cu")
		(at 125.048518 -333.804514 -90)
		(property "Reference" "PC529_P1_4"
			(at 0 0 270)
			(layer "F.SilkS")
			(hide yes)
			(effects
				(font
					(size 1.27 1.27)
				)
			)
		)
		(property "Value" ""
			(at 0 0 270)
			(layer "F.Fab")
			(effects
				(font
					(size 1.27 1.27)
				)
			)
		)
		(duplicate_pad_numbers_are_jumpers no)
		(fp_line
			(start -0.7874 0.4064)
			(end -0.7874 -0.4064)
			(stroke
				(width 0.1524)
				(type default)
			)
			(layer "F.SilkS")
		)
		(fp_line
			(start 0.7874 0.4064)
			(end -0.7874 0.4064)
			(stroke
				(width 0.1524)
				(type default)
			)
			(layer "F.SilkS")
		)
		(fp_line
			(start -0.7874 -0.4064)
			(end 0.7874 -0.4064)
			(stroke
				(width 0.1524)
				(type default)
			)
			(layer "F.SilkS")
		)
		(fp_line
			(start 0.7874 -0.4064)
			(end 0.7874 0.4064)
			(stroke
				(width 0.1524)
				(type default)
			)
			(layer "F.SilkS")
		)
		(fp_line
			(start -0.67945 0.3048)
			(end -0.67945 -0.305054)
			(stroke
				(width 0.1)
				(type default)
			)
			(layer "F.Fab")
		)
		(fp_line
			(start -0.12065 0.3048)
			(end -0.67945 0.3048)
			(stroke
				(width 0.1)
				(type default)
			)
			(layer "F.Fab")
		)
		(fp_line
			(start 0.120396 0.3048)
			(end 0.120396 0.2794)
			(stroke
				(width 0.1)
				(type default)
			)
			(layer "F.Fab")
		)
		(fp_line
			(start 0.67945 0.3048)
			(end 0.120396 0.3048)
			(stroke
				(width 0.1)
				(type default)
			)
			(layer "F.Fab")
		)
		(fp_line
			(start -0.12065 0.2794)
			(end -0.12065 0.3048)
			(stroke
				(width 0.1)
				(type default)
			)
			(layer "F.Fab")
		)
		(fp_line
			(start 0.120396 0.2794)
			(end -0.12065 0.2794)
			(stroke
				(width 0.1)
				(type default)
			)
			(layer "F.Fab")
		)
		(fp_line
			(start -0.12065 -0.2794)
			(end 0.12065 -0.2794)
			(stroke
				(width 0.1)
				(type default)
			)
			(layer "F.Fab")
		)
		(fp_line
			(start 0.12065 -0.2794)
			(end 0.12065 -0.3048)
			(stroke
				(width 0.1)
				(type default)
			)
			(layer "F.Fab")
		)
		(fp_line
			(start 0.12065 -0.3048)
			(end 0.67945 -0.3048)
			(stroke
				(width 0.1)
				(type default)
			)
			(layer "F.Fab")
		)
		(fp_line
			(start 0.67945 -0.3048)
			(end 0.67945 0.3048)
			(stroke
				(width 0.1)
				(type default)
			)
			(layer "F.Fab")
		)
		(fp_line
			(start -0.67945 -0.305054)
			(end -0.12065 -0.305054)
			(stroke
				(width 0.1)
				(type default)
			)
			(layer "F.Fab")
		)
		(fp_line
			(start -0.12065 -0.305054)
			(end -0.12065 -0.2794)
			(stroke
				(width 0.1)
				(type default)
			)
			(layer "F.Fab")
		)
		(pad "1" smd circle
			(at -0.40005 0 270)
			(size 0 0)
			(layers "F.Cu" "F.Mask" "F.Paste")
			(net "SW_P12V_PVCCIN_CPU1_FLT")
		)
		(pad "2" smd circle
			(at 0.40005 0 270)
			(size 0 0)
			(layers "F.Cu" "F.Mask" "F.Paste")
			(net "GND")
		)
	)
	(footprint ""
		(layer "F.Cu")
		(at 347.754448 -402.371052 -90)
		(property "Reference" "C1792"
			(at 0 0 270)
			(layer "F.SilkS")
			(hide yes)
			(effects
				(font
					(size 1.27 1.27)
				)
			)
		)
		(property "Value" ""
			(at 0 0 270)
			(layer "F.Fab")
			(effects
				(font
					(size 1.27 1.27)
				)
			)
		)
		(duplicate_pad_numbers_are_jumpers no)
		(fp_line
			(start -0.299974 0.150114)
			(end -0.299974 -0.150114)
			(stroke
				(width 0.1)
				(type default)
			)
			(layer "F.Fab")
		)
		(fp_line
			(start 0.299974 0.150114)
			(end -0.299974 0.150114)
			(stroke
				(width 0.1)
				(type default)
			)
			(layer "F.Fab")
		)
		(fp_line
			(start -0.299974 -0.150114)
			(end 0.299974 -0.150114)
			(stroke
				(width 0.1)
				(type default)
			)
			(layer "F.Fab")
		)
		(fp_line
			(start 0.299974 -0.150114)
			(end 0.299974 0.150114)
			(stroke
				(width 0.1)
				(type default)
			)
			(layer "F.Fab")
		)
		(pad "1" smd rect
			(at -0.2667 0 270)
			(size 0.3048 0.381)
			(layers "F.Cu" "F.Mask" "F.Paste")
			(net "P5E_CPU0_PE4_TX_C_DP<14>")
		)
		(pad "2" smd rect
			(at 0.2667 0 270)
			(size 0.3048 0.381)
			(layers "F.Cu" "F.Mask" "F.Paste")
			(net "P5E_CPU0_PE4_TX_DP<14>")
		)
	)
)
